(kicad_pcb
	(version 20241229)
	(generator "pcbnew")
	(generator_version "9.0")
	(general
		(thickness 1.6296)
		(legacy_teardrops no)
	)
	(paper "A3")
	(title_block
		(title "Thunderbolt to 10GbE adapter")
		(date "2026-04-21")
		(rev "1.1.0")
		(company "Antmicro Ltd")
		(comment 1 "www.antmicro.com")
		(comment 9 "footprints 426-430 of 703")
	)
	(layers
		(0 "F.Cu" signal)
		(4 "In1.Cu" signal)
		(6 "In2.Cu" signal)
		(8 "In3.Cu" signal)
		(10 "In4.Cu" signal)
		(12 "In5.Cu" signal)
		(14 "In6.Cu" signal)
		(2 "B.Cu" signal)
		(9 "F.Adhes" user "F.Adhesive")
		(11 "B.Adhes" user "B.Adhesive")
		(13 "F.Paste" user)
		(15 "B.Paste" user)
		(5 "F.SilkS" user "F.Silkscreen")
		(7 "B.SilkS" user "B.Silkscreen")
		(1 "F.Mask" user)
		(3 "B.Mask" user)
		(17 "Dwgs.User" user "User.Drawings")
		(19 "Cmts.User" user "User.Comments")
		(21 "Eco1.User" user "User.Eco1")
		(23 "Eco2.User" user "User.Eco2")
		(25 "Edge.Cuts" user)
		(27 "Margin" user)
		(31 "F.CrtYd" user "F.Courtyard")
		(29 "B.CrtYd" user "B.Courtyard")
		(35 "F.Fab" user)
		(33 "B.Fab" user)
	)
	(footprint "antmicro-footprints:C_0402_1005Metric"
		(layer "B.Cu")
		(at 128.5 123.95 -90)
		(descr "Capacitor SMD 0402")
		(tags "capacitor SMD 0402")
		(property "Reference" "C69"
			(at -7.700002 -21.900002 90)
			(layer "B.SilkS")
			(effects
				(font
					(size 0.7 0.7)
					(thickness 0.15)
				)
				(justify mirror)
			)
		)
		(property "Value" "C_1u_0402"
			(at -1.022927 -2.155213 90)
			(layer "B.Fab")
			(effects
				(font
					(size 0.7 0.7)
					(thickness 0.15)
				)
				(justify left bottom mirror)
			)
		)
		(property "Datasheet" "https://product.tdk.com/en/search/capacitor/ceramic/mlcc/info?part_no=C1005X6S1A105K050BC"
			(at 0 0 90)
			(layer "B.Fab")
			(hide yes)
			(effects
				(font
					(size 1.27 1.27)
					(thickness 0.15)
				)
				(justify mirror)
			)
		)
		(property "Description" "SMD Multilayer Ceramic Capacitor, 1 µF, 10 V, 0402 [1005 Metric], ± 10%, X6S, C"
			(at 0 0 90)
			(layer "B.Fab")
			(hide yes)
			(effects
				(font
					(size 1.27 1.27)
					(thickness 0.15)
				)
				(justify mirror)
			)
		)
		(property "MPN" "C1005X6S1A105K050BC"
			(at 0 0 270)
			(unlocked yes)
			(layer "B.Fab")
			(hide yes)
			(effects
				(font
					(size 1 1)
					(thickness 0.15)
				)
				(justify mirror)
			)
		)
		(property "Manufacturer" "TDK"
			(at 0 0 270)
			(unlocked yes)
			(layer "B.Fab")
			(hide yes)
			(effects
				(font
					(size 1 1)
					(thickness 0.15)
				)
				(justify mirror)
			)
		)
		(property "License" "Apache-2.0"
			(at 0 0 270)
			(unlocked yes)
			(layer "B.Fab")
			(hide yes)
			(effects
				(font
					(size 1 1)
					(thickness 0.15)
				)
				(justify mirror)
			)
		)
		(property "Val" "1u"
			(at 0 0 270)
			(unlocked yes)
			(layer "B.Fab")
			(hide yes)
			(effects
				(font
					(size 1 1)
					(thickness 0.15)
				)
				(justify mirror)
			)
		)
		(property "Voltage" ""
			(at 0 0 270)
			(unlocked yes)
			(layer "B.Fab")
			(hide yes)
			(effects
				(font
					(size 1 1)
					(thickness 0.15)
				)
				(justify mirror)
			)
		)
		(property "Dielectric" ""
			(at 0 0 270)
			(unlocked yes)
			(layer "B.Fab")
			(hide yes)
			(effects
				(font
					(size 1 1)
					(thickness 0.15)
				)
				(justify mirror)
			)
		)
		(property "Author" "Antmicro"
			(at 0 0 270)
			(unlocked yes)
			(layer "B.Fab")
			(hide yes)
			(effects
				(font
					(size 1 1)
					(thickness 0.15)
				)
				(justify mirror)
			)
		)
		(sheetname "/TB Controller - Power/")
		(sheetfile "tb-power.kicad_sch")
		(attr smd)
		(fp_rect
			(start -0.925 0.47)
			(end 0.925 -0.47)
			(stroke
				(width 0.05)
				(type default)
			)
			(fill no)
			(layer "B.CrtYd")
		)
		(fp_line
			(start -0.494 0.25)
			(end 0.504 0.25)
			(stroke
				(width 0.15)
				(type solid)
			)
			(layer "B.Fab")
		)
		(fp_line
			(start 0.504 0.25)
			(end 0.504 -0.248)
			(stroke
				(width 0.15)
				(type solid)
			)
			(layer "B.Fab")
		)
		(fp_line
			(start -0.494 -0.248)
			(end -0.494 0.25)
			(stroke
				(width 0.15)
				(type solid)
			)
			(layer "B.Fab")
		)
		(fp_line
			(start 0.504 -0.248)
			(end -0.494 -0.248)
			(stroke
				(width 0.15)
				(type solid)
			)
			(layer "B.Fab")
		)
		(fp_text user "License: Apache-2.0"
			(at -0.939 -5.799 90)
			(layer "B.Fab")
			(effects
				(font
					(size 0.7 0.7)
					(thickness 0.15)
				)
				(justify left bottom mirror)
			)
		)
		(fp_text user "${REFERENCE}"
			(at -0.939 -4.599 90)
			(layer "B.Fab")
			(effects
				(font
					(size 0.7 0.7)
					(thickness 0.15)
				)
				(justify left bottom mirror)
			)
		)
		(fp_text user "Author: Antmicro"
			(at -0.939 -3.399 90)
			(layer "B.Fab")
			(effects
				(font
					(size 0.7 0.7)
					(thickness 0.15)
				)
				(justify left bottom mirror)
			)
		)
		(pad "1" smd roundrect
			(at -0.48 0 270)
			(size 0.59 0.64)
			(layers "B.Cu" "B.Mask" "B.Paste")
			(roundrect_rratio 0.25)
			(net 23 "GND")
			(pintype "passive")
		)
		(pad "2" smd roundrect
			(at 0.48 0 270)
			(size 0.59 0.64)
			(layers "B.Cu" "B.Mask" "B.Paste")
			(roundrect_rratio 0.25)
			(net 402 "Net-(C52-Pad2)")
			(pintype "passive")
		)
	)
	(footprint "antmicro-footprints:TP_SMD_0.75mm"
		(layer "B.Cu")
		(at 159.731866 67.435118 90)
		(property "Reference" "TP22"
			(at 0.035118 3.268134 180)
			(layer "B.SilkS")
			(effects
				(font
					(size 0.7 0.7)
					(thickness 0.15)
				)
				(justify left bottom mirror)
			)
		)
		(property "Value" "TP_0.75mm_SMD"
			(at 0 -1.2 270)
			(layer "B.Fab")
			(effects
				(font
					(size 0.7 0.7)
					(thickness 0.15)
				)
				(justify left bottom mirror)
			)
		)
		(property "Description" "SMT test point"
			(at 0 0 270)
			(layer "B.Fab")
			(hide yes)
			(effects
				(font
					(size 1.27 1.27)
					(thickness 0.15)
				)
				(justify mirror)
			)
		)
		(property "MPN" ""
			(at 0 0 90)
			(unlocked yes)
			(layer "B.Fab")
			(hide yes)
			(effects
				(font
					(size 1 1)
					(thickness 0.15)
				)
				(justify mirror)
			)
		)
		(property "Manufacturer" ""
			(at 0 0 90)
			(unlocked yes)
			(layer "B.Fab")
			(hide yes)
			(effects
				(font
					(size 1 1)
					(thickness 0.15)
				)
				(justify mirror)
			)
		)
		(property "Author" "Antmicro"
			(at 0 0 90)
			(unlocked yes)
			(layer "B.Fab")
			(hide yes)
			(effects
				(font
					(size 1 1)
					(thickness 0.15)
				)
				(justify mirror)
			)
		)
		(property "License" "Apache-2.0"
			(at 0 0 90)
			(unlocked yes)
			(layer "B.Fab")
			(hide yes)
			(effects
				(font
					(size 1 1)
					(thickness 0.15)
				)
				(justify mirror)
			)
		)
		(sheetname "/X710-AT2 Misc/")
		(sheetfile "x710-at2-mics.kicad_sch")
		(attr exclude_from_pos_files exclude_from_bom)
		(fp_circle
			(center 0 0)
			(end 0.475 0)
			(stroke
				(width 0.05)
				(type default)
			)
			(fill no)
			(layer "B.CrtYd")
		)
		(fp_text user "Author: Antmicro"
			(at -0.4 -3.901 270)
			(layer "B.Fab")
			(effects
				(font
					(size 0.7 0.7)
					(thickness 0.15)
				)
				(justify left bottom mirror)
			)
		)
		(fp_text user "${REFERENCE}"
			(at -0.4 -2.7 270)
			(layer "B.Fab")
			(effects
				(font
					(size 0.7 0.7)
					(thickness 0.15)
				)
				(justify left bottom mirror)
			)
		)
		(fp_text user "License: Apache-2.0"
			(at -0.4 -5.101 270)
			(layer "B.Fab")
			(effects
				(font
					(size 0.7 0.7)
					(thickness 0.15)
				)
				(justify left bottom mirror)
			)
		)
		(pad "1" smd circle
			(at 0 0 90)
			(size 0.75 0.75)
			(layers "B.Cu" "B.Mask")
			(net 141 "/X710-AT2 Misc/NCSI.ARB_OUT")
			(pinfunction "1")
			(pintype "passive")
		)
	)
	(footprint "antmicro-footprints:C_0402_1005Metric"
		(layer "B.Cu")
		(at 162.6 105 90)
		(descr "Capacitor SMD 0402")
		(tags "capacitor SMD 0402")
		(property "Reference" "C152"
			(at 1.4 1.5 270)
			(layer "B.SilkS")
			(effects
				(font
					(size 0.7 0.7)
					(thickness 0.15)
				)
				(justify left bottom mirror)
			)
		)
		(property "Value" "C_100n_0402"
			(at -1.022927 -2.155213 270)
			(layer "B.Fab")
			(effects
				(font
					(size 0.7 0.7)
					(thickness 0.15)
				)
				(justify left bottom mirror)
			)
		)
		(property "Datasheet" "https://www.murata.com/products/productdetail?partno=GRM155R61H104KE14%23"
			(at 0 0 270)
			(layer "B.Fab")
			(hide yes)
			(effects
				(font
					(size 1.27 1.27)
					(thickness 0.15)
				)
				(justify mirror)
			)
		)
		(property "Description" "SMD Multilayer Ceramic Capacitor, 0.1 µF, 50 V, 0402 [1005 Metric], ± 10%, X5R, GRM Series"
			(at 0 0 270)
			(layer "B.Fab")
			(hide yes)
			(effects
				(font
					(size 1.27 1.27)
					(thickness 0.15)
				)
				(justify mirror)
			)
		)
		(property "MPN" "GRM155R61H104KE14D"
			(at 0 0 90)
			(unlocked yes)
			(layer "B.Fab")
			(hide yes)
			(effects
				(font
					(size 1 1)
					(thickness 0.15)
				)
				(justify mirror)
			)
		)
		(property "Manufacturer" "Murata"
			(at 0 0 90)
			(unlocked yes)
			(layer "B.Fab")
			(hide yes)
			(effects
				(font
					(size 1 1)
					(thickness 0.15)
				)
				(justify mirror)
			)
		)
		(property "License" "Apache-2.0"
			(at 0 0 90)
			(unlocked yes)
			(layer "B.Fab")
			(hide yes)
			(effects
				(font
					(size 1 1)
					(thickness 0.15)
				)
				(justify mirror)
			)
		)
		(property "Author" "Antmicro"
			(at 0 0 90)
			(unlocked yes)
			(layer "B.Fab")
			(hide yes)
			(effects
				(font
					(size 1 1)
					(thickness 0.15)
				)
				(justify mirror)
			)
		)
		(property "Val" "100n"
			(at 0 0 90)
			(unlocked yes)
			(layer "B.Fab")
			(hide yes)
			(effects
				(font
					(size 1 1)
					(thickness 0.15)
				)
				(justify mirror)
			)
		)
		(property "Voltage" "50V"
			(at 0 0 90)
			(unlocked yes)
			(layer "B.Fab")
			(hide yes)
			(effects
				(font
					(size 1 1)
					(thickness 0.15)
				)
				(justify mirror)
			)
		)
		(property "Dielectric" "X5R"
			(at 0 0 90)
			(unlocked yes)
			(layer "B.Fab")
			(hide yes)
			(effects
				(font
					(size 1 1)
					(thickness 0.15)
				)
				(justify mirror)
			)
		)
		(sheetname "/X710 DCDC converters/")
		(sheetfile "DCDC_converters_X710.kicad_sch")
		(attr smd)
		(fp_rect
			(start -0.925 0.47)
			(end 0.925 -0.47)
			(stroke
				(width 0.05)
				(type default)
			)
			(fill no)
			(layer "B.CrtYd")
		)
		(fp_line
			(start 0.504 -0.248)
			(end -0.494 -0.248)
			(stroke
				(width 0.15)
				(type solid)
			)
			(layer "B.Fab")
		)
		(fp_line
			(start -0.494 -0.248)
			(end -0.494 0.25)
			(stroke
				(width 0.15)
				(type solid)
			)
			(layer "B.Fab")
		)
		(fp_line
			(start 0.504 0.25)
			(end 0.504 -0.248)
			(stroke
				(width 0.15)
				(type solid)
			)
			(layer "B.Fab")
		)
		(fp_line
			(start -0.494 0.25)
			(end 0.504 0.25)
			(stroke
				(width 0.15)
				(type solid)
			)
			(layer "B.Fab")
		)
		(fp_text user "Author: Antmicro"
			(at -0.939 -3.399 270)
			(layer "B.Fab")
			(effects
				(font
					(size 0.7 0.7)
					(thickness 0.15)
				)
				(justify left bottom mirror)
			)
		)
		(fp_text user "License: Apache-2.0"
			(at -0.939 -5.799 270)
			(layer "B.Fab")
			(effects
				(font
					(size 0.7 0.7)
					(thickness 0.15)
				)
				(justify left bottom mirror)
			)
		)
		(fp_text user "${REFERENCE}"
			(at -0.939 -4.599 270)
			(layer "B.Fab")
			(effects
				(font
					(size 0.7 0.7)
					(thickness 0.15)
				)
				(justify left bottom mirror)
			)
		)
		(pad "1" smd roundrect
			(at -0.48 0 90)
			(size 0.59 0.64)
			(layers "B.Cu" "B.Mask" "B.Paste")
			(roundrect_rratio 0.25)
			(net 23 "GND")
			(pintype "passive")
		)
		(pad "2" smd roundrect
			(at 0.48 0 90)
			(size 0.59 0.64)
			(layers "B.Cu" "B.Mask" "B.Paste")
			(roundrect_rratio 0.25)
			(net 339 "/X710 DCDC converters/+1V0_OUT")
			(pintype "passive")
		)
	)
	(footprint "antmicro-footprints:C_0402_1005Metric"
		(layer "B.Cu")
		(at 157.081867 89.005117)
		(descr "Capacitor SMD 0402")
		(tags "capacitor SMD 0402")
		(property "Reference" "C186"
			(at 18.968134 9.994883 180)
			(layer "B.SilkS")
			(effects
				(font
					(size 0.7 0.7)
					(thickness 0.15)
				)
				(justify mirror)
			)
		)
		(property "Value" "C_1u_25V_0402"
			(at -1.022927 -2.155213 180)
			(layer "B.Fab")
			(effects
				(font
					(size 0.7 0.7)
					(thickness 0.15)
				)
				(justify left bottom mirror)
			)
		)
		(property "Datasheet" "https://www.murata.com/products/productdetail?partno=GRM155R61E105KE11%23"
			(at 0 0 180)
			(layer "B.Fab")
			(hide yes)
			(effects
				(font
					(size 1.27 1.27)
					(thickness 0.15)
				)
				(justify mirror)
			)
		)
		(property "Description" "SMD Multilayer Ceramic Capacitor, 1 µF, 25 V, 0402 [1005 Metric], ± 10%, X5R, GRM Series"
			(at 0 0 180)
			(layer "B.Fab")
			(hide yes)
			(effects
				(font
					(size 1.27 1.27)
					(thickness 0.15)
				)
				(justify mirror)
			)
		)
		(property "MPN" "GRM155R61E105KE11J"
			(at 0 0 0)
			(unlocked yes)
			(layer "B.Fab")
			(hide yes)
			(effects
				(font
					(size 1 1)
					(thickness 0.15)
				)
				(justify mirror)
			)
		)
		(property "Manufacturer" "Murata"
			(at 0 0 0)
			(unlocked yes)
			(layer "B.Fab")
			(hide yes)
			(effects
				(font
					(size 1 1)
					(thickness 0.15)
				)
				(justify mirror)
			)
		)
		(property "License" "Apache-2.0"
			(at 0 0 0)
			(unlocked yes)
			(layer "B.Fab")
			(hide yes)
			(effects
				(font
					(size 1 1)
					(thickness 0.15)
				)
				(justify mirror)
			)
		)
		(property "Author" "Antmicro"
			(at 0 0 0)
			(unlocked yes)
			(layer "B.Fab")
			(hide yes)
			(effects
				(font
					(size 1 1)
					(thickness 0.15)
				)
				(justify mirror)
			)
		)
		(property "Val" "1u"
			(at 0 0 0)
			(unlocked yes)
			(layer "B.Fab")
			(hide yes)
			(effects
				(font
					(size 1 1)
					(thickness 0.15)
				)
				(justify mirror)
			)
		)
		(property "Voltage" "25V"
			(at 0 0 0)
			(unlocked yes)
			(layer "B.Fab")
			(hide yes)
			(effects
				(font
					(size 1 1)
					(thickness 0.15)
				)
				(justify mirror)
			)
		)
		(property "Dielectric" "X5R"
			(at 0 0 0)
			(unlocked yes)
			(layer "B.Fab")
			(hide yes)
			(effects
				(font
					(size 1 1)
					(thickness 0.15)
				)
				(justify mirror)
			)
		)
		(sheetname "/X710-AT2 power/")
		(sheetfile "x710-at2-power.kicad_sch")
		(attr smd)
		(fp_rect
			(start -0.925 0.47)
			(end 0.925 -0.47)
			(stroke
				(width 0.05)
				(type default)
			)
			(fill no)
			(layer "B.CrtYd")
		)
		(fp_line
			(start -0.494 -0.248)
			(end -0.494 0.25)
			(stroke
				(width 0.15)
				(type solid)
			)
			(layer "B.Fab")
		)
		(fp_line
			(start -0.494 0.25)
			(end 0.504 0.25)
			(stroke
				(width 0.15)
				(type solid)
			)
			(layer "B.Fab")
		)
		(fp_line
			(start 0.504 -0.248)
			(end -0.494 -0.248)
			(stroke
				(width 0.15)
				(type solid)
			)
			(layer "B.Fab")
		)
		(fp_line
			(start 0.504 0.25)
			(end 0.504 -0.248)
			(stroke
				(width 0.15)
				(type solid)
			)
			(layer "B.Fab")
		)
		(fp_text user "License: Apache-2.0"
			(at -0.939 -5.799 180)
			(layer "B.Fab")
			(effects
				(font
					(size 0.7 0.7)
					(thickness 0.15)
				)
				(justify left bottom mirror)
			)
		)
		(fp_text user "Author: Antmicro"
			(at -0.939 -3.399 180)
			(layer "B.Fab")
			(effects
				(font
					(size 0.7 0.7)
					(thickness 0.15)
				)
				(justify left bottom mirror)
			)
		)
		(fp_text user "${REFERENCE}"
			(at -0.939 -4.599 180)
			(layer "B.Fab")
			(effects
				(font
					(size 0.7 0.7)
					(thickness 0.15)
				)
				(justify left bottom mirror)
			)
		)
		(pad "1" smd roundrect
			(at -0.48 0)
			(size 0.59 0.64)
			(layers "B.Cu" "B.Mask" "B.Paste")
			(roundrect_rratio 0.25)
			(net 23 "GND")
			(pintype "passive")
		)
		(pad "2" smd roundrect
			(at 0.48 0)
			(size 0.59 0.64)
			(layers "B.Cu" "B.Mask" "B.Paste")
			(roundrect_rratio 0.25)
			(net 10 "AVDDH")
			(pintype "passive")
		)
	)
	(footprint "antmicro-footprints:C_0402_1005Metric"
		(layer "B.Cu")
		(at 121.7 145.1 -90)
		(descr "Capacitor SMD 0402")
		(tags "capacitor SMD 0402")
		(property "Reference" "C4"
			(at -2.35 -0.3 90)
			(layer "B.SilkS")
			(effects
				(font
					(size 0.7 0.7)
					(thickness 0.15)
				)
				(justify left bottom mirror)
			)
		)
		(property "Value" "C_100n_0402"
			(at -1.022927 -2.155213 90)
			(layer "B.Fab")
			(effects
				(font
					(size 0.7 0.7)
					(thickness 0.15)
				)
				(justify left bottom mirror)
			)
		)
		(property "Datasheet" "https://www.murata.com/products/productdetail?partno=GRM155R61H104KE14%23"
			(at 0 0 90)
			(layer "B.Fab")
			(hide yes)
			(effects
				(font
					(size 1.27 1.27)
					(thickness 0.15)
				)
				(justify mirror)
			)
		)
		(property "Description" "SMD Multilayer Ceramic Capacitor, 0.1 µF, 50 V, 0402 [1005 Metric], ± 10%, X5R, GRM Series"
			(at 0 0 90)
			(layer "B.Fab")
			(hide yes)
			(effects
				(font
					(size 1.27 1.27)
					(thickness 0.15)
				)
				(justify mirror)
			)
		)
		(property "MPN" "GRM155R61H104KE14D"
			(at 0 0 270)
			(unlocked yes)
			(layer "B.Fab")
			(hide yes)
			(effects
				(font
					(size 1 1)
					(thickness 0.15)
				)
				(justify mirror)
			)
		)
		(property "Manufacturer" "Murata"
			(at 0 0 270)
			(unlocked yes)
			(layer "B.Fab")
			(hide yes)
			(effects
				(font
					(size 1 1)
					(thickness 0.15)
				)
				(justify mirror)
			)
		)
		(property "License" "Apache-2.0"
			(at 0 0 270)
			(unlocked yes)
			(layer "B.Fab")
			(hide yes)
			(effects
				(font
					(size 1 1)
					(thickness 0.15)
				)
				(justify mirror)
			)
		)
		(property "Val" "100n"
			(at 0 0 270)
			(unlocked yes)
			(layer "B.Fab")
			(hide yes)
			(effects
				(font
					(size 1 1)
					(thickness 0.15)
				)
				(justify mirror)
			)
		)
		(property "Voltage" "50V"
			(at 0 0 270)
			(unlocked yes)
			(layer "B.Fab")
			(hide yes)
			(effects
				(font
					(size 1 1)
					(thickness 0.15)
				)
				(justify mirror)
			)
		)
		(property "Dielectric" "X5R"
			(at 0 0 270)
			(unlocked yes)
			(layer "B.Fab")
			(hide yes)
			(effects
				(font
					(size 1 1)
					(thickness 0.15)
				)
				(justify mirror)
			)
		)
		(property "Author" "Antmicro"
			(at 0 0 270)
			(unlocked yes)
			(layer "B.Fab")
			(hide yes)
			(effects
				(font
					(size 1 1)
					(thickness 0.15)
				)
				(justify mirror)
			)
		)
		(sheetname "/USB-C connector/")
		(sheetfile "USB-C_connector.kicad_sch")
		(attr smd)
		(fp_rect
			(start -0.925 0.47)
			(end 0.925 -0.47)
			(stroke
				(width 0.05)
				(type default)
			)
			(fill no)
			(layer "B.CrtYd")
		)
		(fp_line
			(start -0.494 0.25)
			(end 0.504 0.25)
			(stroke
				(width 0.15)
				(type solid)
			)
			(layer "B.Fab")
		)
		(fp_line
			(start 0.504 0.25)
			(end 0.504 -0.248)
			(stroke
				(width 0.15)
				(type solid)
			)
			(layer "B.Fab")
		)
		(fp_line
			(start -0.494 -0.248)
			(end -0.494 0.25)
			(stroke
				(width 0.15)
				(type solid)
			)
			(layer "B.Fab")
		)
		(fp_line
			(start 0.504 -0.248)
			(end -0.494 -0.248)
			(stroke
				(width 0.15)
				(type solid)
			)
			(layer "B.Fab")
		)
		(fp_text user "Author: Antmicro"
			(at -0.939 -3.399 90)
			(layer "B.Fab")
			(effects
				(font
					(size 0.7 0.7)
					(thickness 0.15)
				)
				(justify left bottom mirror)
			)
		)
		(fp_text user "License: Apache-2.0"
			(at -0.939 -5.799 90)
			(layer "B.Fab")
			(effects
				(font
					(size 0.7 0.7)
					(thickness 0.15)
				)
				(justify left bottom mirror)
			)
		)
		(fp_text user "${REFERENCE}"
			(at -0.939 -4.599 90)
			(layer "B.Fab")
			(effects
				(font
					(size 0.7 0.7)
					(thickness 0.15)
				)
				(justify left bottom mirror)
			)
		)
		(pad "1" smd roundrect
			(at -0.48 0 270)
			(size 0.59 0.64)
			(layers "B.Cu" "B.Mask" "B.Paste")
			(roundrect_rratio 0.25)
			(net 23 "GND")
			(pintype "passive")
		)
		(pad "2" smd roundrect
			(at 0.48 0 270)
			(size 0.59 0.64)
			(layers "B.Cu" "B.Mask" "B.Paste")
			(roundrect_rratio 0.25)
			(net 215 "/USB-C connector/VBUS")
			(pintype "passive")
		)
	)
)
